FILE_TYPE = CONNECTIVITY;
{Allegro Design Entry HDL 17.2-2016 S081 (4005846) 1/11/2022}
"PAGE_NUMBER" = 36;
0"NC";
1"PVCCIN_CPU0\g";
2"PVCCIN_CPU0\g";
3"PVCCIN_CPU0\g";
4"PVCCIN_CPU0\g";
%"SOCKET4677_AZIF0045P001C01CS"
"26","(-1000,1375)","0","pure_quanta","I1";
;
PART_NUMBER"DGA^7000023"
VALUE"SOCKET4677_AZIF0045-P001C01CS"
MATERIAL"IO"
PART_TYPE"SMLF"
$LOCATION"U2"
CDS_LMAN_SYM_OUTLINE"-1050,2000,1050,-2000"
NEEDS_NO_SIZE"TRUE"
CDS_LIB"pure_quanta"
CDS_LOCATION"U2"
$SEC"26"
CDS_SEC"26";
"VCCIN190"
$PN"BW80"3;
"VCCIN191"
$PN"BW82"3;
"VCCIN192"
$PN"BW84"3;
"VCCIN193"
$PN"BW86"3;
"VCCIN194"
$PN"BW88"3;
"VCCIN195"
$PN"BW90"3;
"VCCIN196"
$PN"BY32"3;
"VCCIN197"
$PN"BY34"3;
"VCCIN198"
$PN"BY36"3;
"VCCIN199"
$PN"BY38"3;
"VCCIN200"
$PN"BY40"3;
"VCCIN201"
$PN"BY42"3;
"VCCIN202"
$PN"BY44"3;
"VCCIN203"
$PN"BY47"3;
"VCCIN204"
$PN"BY49"3;
"VCCIN205"
$PN"BY51"3;
"VCCIN206"
$PN"BY53"3;
"VCCIN207"
$PN"BY55"3;
"VCCIN208"
$PN"BY57"3;
"VCCIN209"
$PN"BY59"3;
"VCCIN210"
$PN"BY61"3;
"VCCIN211"
$PN"BY63"3;
"VCCIN212"
$PN"BY65"3;
"VCCIN213"
$PN"BY67"3;
"VCCIN214"
$PN"BY69"3;
"VCCIN215"
$PN"BY71"3;
"VCCIN216"
$PN"BY73"3;
"VCCIN217"
$PN"BY75"3;
"VCCIN218"
$PN"BY77"3;
"VCCIN219"
$PN"BY79"3;
"VCCIN220"
$PN"BY81"3;
"VCCIN221"
$PN"BY83"3;
"VCCIN222"
$PN"BY85"3;
"VCCIN223"
$PN"BY87"3;
"VCCIN224"
$PN"BY89"3;
"VCCIN225"
$PN"CA33"3;
"VCCIN226"
$PN"CA35"3;
"VCCIN227"
$PN"CA37"3;
"VCCIN228"
$PN"CA39"3;
"VCCIN229"
$PN"CA41"3;
"VCCIN230"
$PN"CA43"3;
"VCCIN231"
$PN"CA45"3;
"VCCIN232"
$PN"CA48"3;
"VCCIN233"
$PN"CA50"3;
"VCCIN234"
$PN"CA52"3;
"VCCIN235"
$PN"CA54"3;
"VCCIN236"
$PN"CA56"3;
"VCCIN237"
$PN"CA58"3;
"VCCIN238"
$PN"CA60"3;
"VCCIN239"
$PN"CA62"3;
"VCCIN240"
$PN"CA64"3;
"VCCIN241"
$PN"CA66"3;
"VCCIN242"
$PN"CA68"3;
"VCCIN243"
$PN"CA70"3;
"VCCIN244"
$PN"CA72"3;
"VCCIN245"
$PN"CA74"3;
"VCCIN246"
$PN"CA76"3;
"VCCIN247"
$PN"CA78"3;
"VCCIN248"
$PN"CA80"3;
"VCCIN249"
$PN"CA82"3;
"VCCIN250"
$PN"CA84"3;
"VCCIN251"
$PN"CA86"3;
"VCCIN252"
$PN"CA88"3;
"VCCIN253"
$PN"CA90"3;
"VCCIN254"
$PN"CB61"3;
"VCCIN255"
$PN"CB75"3;
"VCCIN256"
$PN"CB77"3;
"VCCIN257"
$PN"CC33"3;
"VCCIN258"
$PN"CC35"3;
"VCCIN259"
$PN"CC37"3;
"VCCIN260"
$PN"CC39"3;
"VCCIN261"
$PN"CC41"3;
"VCCIN262"
$PN"CC43"3;
"VCCIN263"
$PN"CC45"3;
"VCCIN264"
$PN"CC48"3;
"VCCIN265"
$PN"CC50"4;
"VCCIN266"
$PN"CC52"4;
"VCCIN267"
$PN"CC54"4;
"VCCIN268"
$PN"CC56"4;
"VCCIN269"
$PN"CC58"4;
"VCCIN270"
$PN"CC60"4;
"VCCIN271"
$PN"CC76"4;
"VCCIN272"
$PN"CC78"4;
"VCCIN273"
$PN"CC80"4;
"VCCIN274"
$PN"CC82"4;
"VCCIN275"
$PN"CC84"4;
"VCCIN276"
$PN"CC86"4;
"VCCIN277"
$PN"CC88"4;
"VCCIN278"
$PN"CC90"4;
"VCCIN279"
$PN"CD32"4;
"VCCIN280"
$PN"CD34"4;
"VCCIN281"
$PN"CD36"4;
"VCCIN282"
$PN"CD38"4;
"VCCIN283"
$PN"CD40"4;
"VCCIN284"
$PN"CD42"4;
"VCCIN285"
$PN"CD44"4;
"VCCIN286"
$PN"CD47"4;
"VCCIN287"
$PN"CD49"4;
"VCCIN288"
$PN"CD51"4;
"VCCIN289"
$PN"CD53"4;
"VCCIN290"
$PN"CD55"4;
"VCCIN291"
$PN"CD57"4;
"VCCIN292"
$PN"CD59"4;
"VCCIN293"
$PN"CD79"4;
"VCCIN294"
$PN"CD81"4;
"VCCIN295"
$PN"CD83"4;
"VCCIN296"
$PN"CD85"4;
"VCCIN297"
$PN"CD87"4;
"VCCIN298"
$PN"CD89"4;
"VCCIN299"
$PN"CE80"4;
"VCCIN300"
$PN"CE82"4;
"VCCIN301"
$PN"CE84"4;
"VCCIN302"
$PN"CE86"4;
"VCCIN303"
$PN"CE88"4;
"VCCIN304"
$PN"CE90"4;
"VCCIN305"
$PN"CF79"4;
"VCCIN306"
$PN"CF81"4;
"VCCIN307"
$PN"CF83"4;
"VCCIN308"
$PN"CF85"4;
"VCCIN309"
$PN"CF87"4;
"VCCIN310"
$PN"CF89"4;
"VCCIN311"
$PN"CF91"4;
"VCCIN312"
$PN"CG80"4;
"VCCIN313"
$PN"CG82"4;
"VCCIN314"
$PN"CG84"4;
"VCCIN315"
$PN"CG86"4;
"VCCIN316"
$PN"CG88"4;
"VCCIN317"
$PN"CG90"4;
"VCCIN318"
$PN"CH81"4;
"VCCIN319"
$PN"CH91"4;
"VCCIN320"
$PN"CJ82"4;
"VCCIN321"
$PN"CJ84"4;
"VCCIN322"
$PN"CJ86"4;
"VCCIN323"
$PN"CJ88"4;
"VCCIN324"
$PN"CJ90"4;
"VCCIN325"
$PN"CK83"4;
"VCCIN326"
$PN"CK85"4;
"VCCIN327"
$PN"CK87"4;
"VCCIN328"
$PN"CK89"4;
"VCCIN329"
$PN"CK91"4;
"VCCIN330"
$PN"CL84"4;
"VCCIN331"
$PN"CL86"4;
"VCCIN332"
$PN"CL88"4;
"VCCIN333"
$PN"CL90"4;
"VCCIN334"
$PN"CM87"4;
"VCCIN335"
$PN"CM91"4;
"VCCIN336"
$PN"CN88"4;
"VCCIN337"
$PN"CN90"4;
"VCCIN338"
$PN"CP89"4;
"VCCIN339"
$PN"CM89"4;
%"VCC_CORE"
"1","(-2450,3450)","0","logical_power","I2";
;
HDL_POWER"PVCCIN_CPU0"
CDS_LIB"logical_power";
"A"4;
%"VCC_CORE"
"1","(450,3450)","0","logical_power","I3";
;
HDL_POWER"PVCCIN_CPU0"
CDS_LIB"logical_power";
"A"3;
%"VCC_CORE"
"1","(4825,3450)","0","logical_power","I5";
;
HDL_POWER"PVCCIN_CPU0"
CDS_LIB"logical_power";
"A"2;
%"VCC_CORE"
"1","(1925,3450)","0","logical_power","I6";
;
HDL_POWER"PVCCIN_CPU0"
CDS_LIB"logical_power";
"A"1;
%"SOCKET4677_AZIF0045P001C01CS"
"27","(3375,1375)","0","pure_quanta","I7";
;
PART_NUMBER"DGA^7000023"
VALUE"SOCKET4677_AZIF0045-P001C01CS"
MATERIAL"IO"
PART_TYPE"SMLF"
$LOCATION"U2"
CDS_LMAN_SYM_OUTLINE"-1050,2000,1050,-2000"
NEEDS_NO_SIZE"TRUE"
CDS_LIB"pure_quanta"
CDS_LOCATION"U2"
$SEC"27"
CDS_SEC"27";
"VCCIN40"
$PN"BN43"2;
"VCCIN41"
$PN"BN45"2;
"VCCIN42"
$PN"BN48"2;
"VCCIN43"
$PN"BN50"2;
"VCCIN44"
$PN"BN52"2;
"VCCIN45"
$PN"BN54"2;
"VCCIN46"
$PN"BN56"2;
"VCCIN47"
$PN"BN58"2;
"VCCIN48"
$PN"BN60"2;
"VCCIN49"
$PN"BN78"2;
"VCCIN50"
$PN"BN80"2;
"VCCIN51"
$PN"BN82"2;
"VCCIN52"
$PN"BN84"2;
"VCCIN53"
$PN"BN86"2;
"VCCIN54"
$PN"BN88"2;
"VCCIN55"
$PN"BN90"2;
"VCCIN56"
$PN"BP32"2;
"VCCIN57"
$PN"BP34"2;
"VCCIN58"
$PN"BP36"2;
"VCCIN59"
$PN"BP38"2;
"VCCIN60"
$PN"BP40"2;
"VCCIN61"
$PN"BP42"2;
"VCCIN62"
$PN"BP44"2;
"VCCIN63"
$PN"BP47"2;
"VCCIN64"
$PN"BP49"2;
"VCCIN65"
$PN"BP51"2;
"VCCIN66"
$PN"BP53"2;
"VCCIN67"
$PN"BP55"2;
"VCCIN68"
$PN"BP57"2;
"VCCIN69"
$PN"BP59"2;
"VCCIN70"
$PN"BP61"2;
"VCCIN71"
$PN"BP79"2;
"VCCIN72"
$PN"BP81"2;
"VCCIN73"
$PN"BP83"2;
"VCCIN74"
$PN"BP85"2;
"VCCIN75"
$PN"BP87"2;
"VCCIN76"
$PN"BP89"2;
"VCCIN77"
$PN"BR60"2;
"VCCIN78"
$PN"BR62"2;
"VCCIN79"
$PN"BR78"2;
"VCCIN80"
$PN"BT32"2;
"VCCIN81"
$PN"BT34"2;
"VCCIN82"
$PN"BT36"2;
"VCCIN83"
$PN"BT38"2;
"VCCIN84"
$PN"BT40"2;
"VCCIN85"
$PN"BT42"2;
"VCCIN86"
$PN"BT44"2;
"VCCIN87"
$PN"BT47"2;
"VCCIN88"
$PN"BT49"2;
"VCCIN89"
$PN"BT51"2;
"VCCIN90"
$PN"BT53"2;
"VCCIN91"
$PN"BT55"2;
"VCCIN92"
$PN"BT57"2;
"VCCIN93"
$PN"BT59"2;
"VCCIN94"
$PN"BT61"2;
"VCCIN95"
$PN"BT63"2;
"VCCIN96"
$PN"BT65"2;
"VCCIN97"
$PN"BT67"2;
"VCCIN98"
$PN"BT69"2;
"VCCIN99"
$PN"BT71"2;
"VCCIN100"
$PN"BT73"2;
"VCCIN101"
$PN"BT75"2;
"VCCIN102"
$PN"BT77"2;
"VCCIN103"
$PN"BT79"2;
"VCCIN104"
$PN"BT81"2;
"VCCIN105"
$PN"BT83"2;
"VCCIN106"
$PN"BT85"2;
"VCCIN107"
$PN"BT87"2;
"VCCIN108"
$PN"BT89"2;
"VCCIN109"
$PN"BU33"2;
"VCCIN110"
$PN"BU35"2;
"VCCIN111"
$PN"BU37"2;
"VCCIN112"
$PN"BU39"2;
"VCCIN113"
$PN"BU41"2;
"VCCIN114"
$PN"BU43"2;
"VCCIN115"
$PN"BU45"1;
"VCCIN116"
$PN"BU48"1;
"VCCIN117"
$PN"BU50"1;
"VCCIN118"
$PN"BU52"1;
"VCCIN119"
$PN"BU54"1;
"VCCIN120"
$PN"BU56"1;
"VCCIN121"
$PN"BU58"1;
"VCCIN122"
$PN"BU60"1;
"VCCIN123"
$PN"BU62"1;
"VCCIN124"
$PN"BU64"1;
"VCCIN125"
$PN"BU66"1;
"VCCIN126"
$PN"BU68"1;
"VCCIN127"
$PN"BU70"1;
"VCCIN128"
$PN"BU72"1;
"VCCIN129"
$PN"BU74"1;
"VCCIN130"
$PN"BU76"1;
"VCCIN131"
$PN"BU78"1;
"VCCIN132"
$PN"BU80"1;
"VCCIN133"
$PN"BU82"1;
"VCCIN134"
$PN"BU84"1;
"VCCIN135"
$PN"BU86"1;
"VCCIN136"
$PN"BU88"1;
"VCCIN137"
$PN"BU90"1;
"VCCIN138"
$PN"BV32"1;
"VCCIN139"
$PN"BV34"1;
"VCCIN140"
$PN"BV36"1;
"VCCIN141"
$PN"BV38"1;
"VCCIN142"
$PN"BV40"1;
"VCCIN143"
$PN"BV42"1;
"VCCIN144"
$PN"BV44"1;
"VCCIN145"
$PN"BV47"1;
"VCCIN146"
$PN"BV49"1;
"VCCIN147"
$PN"BV51"1;
"VCCIN148"
$PN"BV53"1;
"VCCIN149"
$PN"BV55"1;
"VCCIN150"
$PN"BV57"1;
"VCCIN151"
$PN"BV59"1;
"VCCIN152"
$PN"BV61"1;
"VCCIN153"
$PN"BV63"1;
"VCCIN154"
$PN"BV65"1;
"VCCIN155"
$PN"BV67"1;
"VCCIN156"
$PN"BV69"1;
"VCCIN157"
$PN"BV71"1;
"VCCIN158"
$PN"BV73"1;
"VCCIN159"
$PN"BV75"1;
"VCCIN160"
$PN"BV77"1;
"VCCIN161"
$PN"BV79"1;
"VCCIN162"
$PN"BV81"1;
"VCCIN163"
$PN"BV83"1;
"VCCIN164"
$PN"BV85"1;
"VCCIN165"
$PN"BV87"1;
"VCCIN166"
$PN"BV89"1;
"VCCIN167"
$PN"BW33"1;
"VCCIN168"
$PN"BW35"1;
"VCCIN169"
$PN"BW37"1;
"VCCIN170"
$PN"BW39"1;
"VCCIN171"
$PN"BW41"1;
"VCCIN172"
$PN"BW43"1;
"VCCIN173"
$PN"BW45"1;
"VCCIN174"
$PN"BW48"1;
"VCCIN175"
$PN"BW50"1;
"VCCIN176"
$PN"BW52"1;
"VCCIN177"
$PN"BW54"1;
"VCCIN178"
$PN"BW56"1;
"VCCIN179"
$PN"BW58"1;
"VCCIN180"
$PN"BW60"1;
"VCCIN181"
$PN"BW62"1;
"VCCIN182"
$PN"BW64"1;
"VCCIN183"
$PN"BW66"1;
"VCCIN184"
$PN"BW68"1;
"VCCIN185"
$PN"BW70"1;
"VCCIN186"
$PN"BW72"1;
"VCCIN187"
$PN"BW74"1;
"VCCIN188"
$PN"BW76"1;
"VCCIN189"
$PN"BW78"1;
END.
